# S9S_MB_2U (Grand Teton) — schematic netlist excerpt (pin names and nets, part order shuffled) for the footprints in the layout excerpt that follows; sources: Cadence DE-HDL packaged netlist, KiCad conversion of 03242023_DA0F0TMBIJ0_F0T_Motherboard_J_brd_V01_OCP.brd

R2241  Q_RES  1K 1% CHIP  pkg 0402LF  page 195 : A = FM_BOARD_SKU_ID1 ; B = GND
C889  Q_CAP_DIFFBUS  DIFF BUS_0.22UF 6.3V 20% X6S  pkg C0201  page 174 : \1\ = P5E_CPU0_PE3_TX_C_DP<6> ; \2\ = P5E_CPU0_PE3_TX_DP<6>
R3337  Q_RES  0 5% CHIP  pkg 0402LF  page 212 : A = CLK_100M_GPU_FPGA_DP_R ; B = CLK_100M_GPU_FPGA_DP

(kicad_pcb
	(version 20260206)
	(generator "pcbnew")
	(generator_version "10.0")
	(general
		(thickness 1.6)
		(legacy_teardrops no)
	)
	(paper "A4")
	(title_block
		(title "03242023_DA0F0TMBIJ0_F0T_Motherboard_J_brd_V01_OCP.brd")
		(comment 1 "Grand Teton / footprints 3913-3915 of 6105")
	)
	(layers
		(0 "F.Cu" signal "TOP")
		(4 "In1.Cu" signal "GND")
		(6 "In2.Cu" signal "IN1")
		(8 "In3.Cu" signal "GND1")
		(10 "In4.Cu" signal "IN2")
		(12 "In5.Cu" signal "GND2")
		(14 "In6.Cu" signal "IN3")
		(16 "In7.Cu" signal "GND3")
		(18 "In8.Cu" signal "VCC")
		(20 "In9.Cu" signal "VCC1")
		(22 "In10.Cu" signal "GND4")
		(24 "In11.Cu" signal "IN4")
		(26 "In12.Cu" signal "GND5")
		(28 "In13.Cu" signal "IN5")
		(30 "In14.Cu" signal "GND6")
		(32 "In15.Cu" signal "IN6")
		(34 "In16.Cu" signal "GND7")
		(2 "B.Cu" signal "BOTTOM")
		(9 "F.Adhes" user "F.Adhesive")
		(11 "B.Adhes" user "B.Adhesive")
		(13 "F.Paste" user "Package Geometry/Pastemask Top")
		(15 "B.Paste" user "Package Geometry/Pastemask Bottom")
		(5 "F.SilkS" user "Ref Des/Silkscreen Top")
		(7 "B.SilkS" user "Ref Des/Silkscreen Bottom")
		(1 "F.Mask" user "Board Geometry/Soldermask Top")
		(3 "B.Mask" user "Board Geometry/Soldermask Bottom")
		(17 "Dwgs.User" user "User.Drawings")
		(19 "Cmts.User" user "User.Comments")
		(21 "Eco1.User" user "User.Eco1")
		(23 "Eco2.User" user "User.Eco2")
		(25 "Edge.Cuts" user "Board Geometry/Outline")
		(27 "Margin" user)
		(31 "F.CrtYd" user "Package Geometry/Place Bound Top")
		(29 "B.CrtYd" user "Package Geometry/Place Bound Bottom")
		(35 "F.Fab" user "Ref Des/Assembly Top")
		(33 "B.Fab" user "Ref Des/Assembly Bottom")
	)
	(footprint ""
		(layer "F.Cu")
		(at 401.22729 -408.517344 -90)
		(property "Reference" "C889"
			(at 0 0 270)
			(layer "F.SilkS")
			(hide yes)
			(effects
				(font
					(size 1.27 1.27)
				)
			)
		)
		(property "Value" ""
			(at 0 0 270)
			(layer "F.Fab")
			(effects
				(font
					(size 1.27 1.27)
				)
			)
		)
		(duplicate_pad_numbers_are_jumpers no)
		(fp_line
			(start -0.299974 0.150114)
			(end -0.299974 -0.150114)
			(stroke
				(width 0.1)
				(type default)
			)
			(layer "F.Fab")
		)
		(fp_line
			(start 0.299974 0.150114)
			(end -0.299974 0.150114)
			(stroke
				(width 0.1)
				(type default)
			)
			(layer "F.Fab")
		)
		(fp_line
			(start -0.299974 -0.150114)
			(end 0.299974 -0.150114)
			(stroke
				(width 0.1)
				(type default)
			)
			(layer "F.Fab")
		)
		(fp_line
			(start 0.299974 -0.150114)
			(end 0.299974 0.150114)
			(stroke
				(width 0.1)
				(type default)
			)
			(layer "F.Fab")
		)
		(pad "1" smd rect
			(at -0.2667 0 270)
			(size 0.3048 0.381)
			(layers "F.Cu" "F.Mask" "F.Paste")
			(net "P5E_CPU0_PE3_TX_C_DP<6>")
		)
		(pad "2" smd rect
			(at 0.2667 0 270)
			(size 0.3048 0.381)
			(layers "F.Cu" "F.Mask" "F.Paste")
			(net "P5E_CPU0_PE3_TX_DP<6>")
		)
	)
	(footprint ""
		(layer "F.Cu")
		(at 230.248206 -247.684036 180)
		(property "Reference" "R3337"
			(at 0 0 180)
			(layer "F.SilkS")
			(hide yes)
			(effects
				(font
					(size 1.27 1.27)
				)
			)
		)
		(property "Value" ""
			(at 0 0 180)
			(layer "F.Fab")
			(effects
				(font
					(size 1.27 1.27)
				)
			)
		)
		(duplicate_pad_numbers_are_jumpers no)
		(fp_line
			(start 0.7874 0.4064)
			(end -0.7874 0.4064)
			(stroke
				(width 0.1524)
				(type default)
			)
			(layer "F.SilkS")
		)
		(fp_line
			(start 0.7874 -0.4064)
			(end 0.7874 0.4064)
			(stroke
				(width 0.1524)
				(type default)
			)
			(layer "F.SilkS")
		)
		(fp_line
			(start -0.7874 0.4064)
			(end -0.7874 -0.4064)
			(stroke
				(width 0.1524)
				(type default)
			)
			(layer "F.SilkS")
		)
		(fp_line
			(start -0.7874 -0.4064)
			(end 0.7874 -0.4064)
			(stroke
				(width 0.1524)
				(type default)
			)
			(layer "F.SilkS")
		)
		(fp_line
			(start 0.67945 0.3048)
			(end 0.120396 0.3048)
			(stroke
				(width 0.1)
				(type default)
			)
			(layer "F.Fab")
		)
		(fp_line
			(start 0.67945 -0.3048)
			(end 0.67945 0.3048)
			(stroke
				(width 0.1)
				(type default)
			)
			(layer "F.Fab")
		)
		(fp_line
			(start 0.12065 -0.2794)
			(end 0.12065 -0.3048)
			(stroke
				(width 0.1)
				(type default)
			)
			(layer "F.Fab")
		)
		(fp_line
			(start 0.12065 -0.3048)
			(end 0.67945 -0.3048)
			(stroke
				(width 0.1)
				(type default)
			)
			(layer "F.Fab")
		)
		(fp_line
			(start 0.120396 0.3048)
			(end 0.120396 0.2794)
			(stroke
				(width 0.1)
				(type default)
			)
			(layer "F.Fab")
		)
		(fp_line
			(start 0.120396 0.2794)
			(end -0.12065 0.2794)
			(stroke
				(width 0.1)
				(type default)
			)
			(layer "F.Fab")
		)
		(fp_line
			(start -0.12065 0.3048)
			(end -0.67945 0.3048)
			(stroke
				(width 0.1)
				(type default)
			)
			(layer "F.Fab")
		)
		(fp_line
			(start -0.12065 0.2794)
			(end -0.12065 0.3048)
			(stroke
				(width 0.1)
				(type default)
			)
			(layer "F.Fab")
		)
		(fp_line
			(start -0.12065 -0.2794)
			(end 0.12065 -0.2794)
			(stroke
				(width 0.1)
				(type default)
			)
			(layer "F.Fab")
		)
		(fp_line
			(start -0.12065 -0.305054)
			(end -0.12065 -0.2794)
			(stroke
				(width 0.1)
				(type default)
			)
			(layer "F.Fab")
		)
		(fp_line
			(start -0.67945 0.3048)
			(end -0.67945 -0.305054)
			(stroke
				(width 0.1)
				(type default)
			)
			(layer "F.Fab")
		)
		(fp_line
			(start -0.67945 -0.305054)
			(end -0.12065 -0.305054)
			(stroke
				(width 0.1)
				(type default)
			)
			(layer "F.Fab")
		)
		(pad "1" smd circle
			(at -0.40005 0 180)
			(size 0 0)
			(layers "F.Cu" "F.Mask" "F.Paste")
			(net "CLK_100M_GPU_FPGA_DP_R")
		)
		(pad "2" smd circle
			(at 0.40005 0 180)
			(size 0 0)
			(layers "F.Cu" "F.Mask" "F.Paste")
			(net "CLK_100M_GPU_FPGA_DP")
		)
	)
	(footprint ""
		(layer "F.Cu")
		(at 299.02023 -49.320196 180)
		(property "Reference" "R2241"
			(at 0 0 180)
			(layer "F.SilkS")
			(hide yes)
			(effects
				(font
					(size 1.27 1.27)
				)
			)
		)
		(property "Value" ""
			(at 0 0 180)
			(layer "F.Fab")
			(effects
				(font
					(size 1.27 1.27)
				)
			)
		)
		(duplicate_pad_numbers_are_jumpers no)
		(fp_line
			(start 0.7874 0.4064)
			(end -0.7874 0.4064)
			(stroke
				(width 0.1524)
				(type default)
			)
			(layer "F.SilkS")
		)
		(fp_line
			(start 0.7874 -0.4064)
			(end 0.7874 0.4064)
			(stroke
				(width 0.1524)
				(type default)
			)
			(layer "F.SilkS")
		)
		(fp_line
			(start -0.7874 0.4064)
			(end -0.7874 -0.4064)
			(stroke
				(width 0.1524)
				(type default)
			)
			(layer "F.SilkS")
		)
		(fp_line
			(start -0.7874 -0.4064)
			(end 0.7874 -0.4064)
			(stroke
				(width 0.1524)
				(type default)
			)
			(layer "F.SilkS")
		)
		(fp_line
			(start 0.67945 0.3048)
			(end 0.120396 0.3048)
			(stroke
				(width 0.1)
				(type default)
			)
			(layer "F.Fab")
		)
		(fp_line
			(start 0.67945 -0.3048)
			(end 0.67945 0.3048)
			(stroke
				(width 0.1)
				(type default)
			)
			(layer "F.Fab")
		)
		(fp_line
			(start 0.12065 -0.2794)
			(end 0.12065 -0.3048)
			(stroke
				(width 0.1)
				(type default)
			)
			(layer "F.Fab")
		)
		(fp_line
			(start 0.12065 -0.3048)
			(end 0.67945 -0.3048)
			(stroke
				(width 0.1)
				(type default)
			)
			(layer "F.Fab")
		)
		(fp_line
			(start 0.120396 0.3048)
			(end 0.120396 0.2794)
			(stroke
				(width 0.1)
				(type default)
			)
			(layer "F.Fab")
		)
		(fp_line
			(start 0.120396 0.2794)
			(end -0.12065 0.2794)
			(stroke
				(width 0.1)
				(type default)
			)
			(layer "F.Fab")
		)
		(fp_line
			(start -0.12065 0.3048)
			(end -0.67945 0.3048)
			(stroke
				(width 0.1)
				(type default)
			)
			(layer "F.Fab")
		)
		(fp_line
			(start -0.12065 0.2794)
			(end -0.12065 0.3048)
			(stroke
				(width 0.1)
				(type default)
			)
			(layer "F.Fab")
		)
		(fp_line
			(start -0.12065 -0.2794)
			(end 0.12065 -0.2794)
			(stroke
				(width 0.1)
				(type default)
			)
			(layer "F.Fab")
		)
		(fp_line
			(start -0.12065 -0.305054)
			(end -0.12065 -0.2794)
			(stroke
				(width 0.1)
				(type default)
			)
			(layer "F.Fab")
		)
		(fp_line
			(start -0.67945 0.3048)
			(end -0.67945 -0.305054)
			(stroke
				(width 0.1)
				(type default)
			)
			(layer "F.Fab")
		)
		(fp_line
			(start -0.67945 -0.305054)
			(end -0.12065 -0.305054)
			(stroke
				(width 0.1)
				(type default)
			)
			(layer "F.Fab")
		)
		(pad "1" smd circle
			(at -0.40005 0 180)
			(size 0 0)
			(layers "F.Cu" "F.Mask" "F.Paste")
			(net "FM_BOARD_SKU_ID1")
		)
		(pad "2" smd circle
			(at 0.40005 0 180)
			(size 0 0)
			(layers "F.Cu" "F.Mask" "F.Paste")
			(net "GND")
		)
	)
)
